# BASEBOARD_FAB2 (Tioga Pass) — schematic netlist excerpt (pin names and nets, part order shuffled) for the footprints in the layout excerpt that follows; sources: Cadence DE-HDL packaged netlist, KiCad conversion of Wiwynn_Tioga_Pass_MB.brd

R2U26  RES  0.0 5% CHIP  pkg 0402  page 107 : A = P3E_CPU0_PE1_SS_RXP<6> ; B = P3E_CPU0_PE1_SS_R_RXP<6>
C3P43  CAP_A  0.1UF 16V 10% X7R  pkg 0402V  page 192 : A = P3V3_STBY ; B = GND
R2T34  RES  4.75K 1% CHIP  pkg 0402  page 156 : A = P3V3_STBY ; B = FM_BMC_PWRBTN_OUT_N

(kicad_pcb
	(version 20260206)
	(generator "pcbnew")
	(generator_version "10.0")
	(general
		(thickness 1.6)
		(legacy_teardrops no)
	)
	(paper "A4")
	(title_block
		(title "Wiwynn_Tioga_Pass_MB.brd")
		(comment 1 "Tioga Pass / footprints 4339-4341 of 4770")
	)
	(layers
		(0 "F.Cu" signal "TOP")
		(4 "In1.Cu" signal "L2GND")
		(6 "In2.Cu" signal "L3")
		(8 "In3.Cu" signal "L4GND")
		(10 "In4.Cu" signal "L5")
		(12 "In5.Cu" signal "L6GND")
		(14 "In6.Cu" signal "L7VCC")
		(16 "In7.Cu" signal "L8VCC")
		(18 "In8.Cu" signal "L9GND")
		(20 "In9.Cu" signal "L10")
		(22 "In10.Cu" signal "L11GND")
		(24 "In11.Cu" signal "L12")
		(26 "In12.Cu" signal "L13GND")
		(2 "B.Cu" signal "BOTTOM")
		(9 "F.Adhes" user "F.Adhesive")
		(11 "B.Adhes" user "B.Adhesive")
		(13 "F.Paste" user "Package Geometry/Pastemask Top")
		(15 "B.Paste" user "Package Geometry/Pastemask Bottom")
		(5 "F.SilkS" user "Ref Des/Silkscreen Top")
		(7 "B.SilkS" user "Ref Des/Silkscreen Bottom")
		(1 "F.Mask" user "Board Geometry/Soldermask Top")
		(3 "B.Mask" user "Board Geometry/Soldermask Bottom")
		(17 "Dwgs.User" user "User.Drawings")
		(19 "Cmts.User" user "User.Comments")
		(21 "Eco1.User" user "User.Eco1")
		(23 "Eco2.User" user "User.Eco2")
		(25 "Edge.Cuts" user "Board Geometry/Outline")
		(27 "Margin" user)
		(31 "F.CrtYd" user "Package Geometry/Place Bound Top")
		(29 "B.CrtYd" user "Package Geometry/Place Bound Bottom")
		(35 "F.Fab" user "Ref Des/Assembly Top")
		(33 "B.Fab" user "Ref Des/Assembly Bottom")
	)
	(footprint ""
		(layer "B.Cu")
		(at 398.272 -27.432 180)
		(property "Reference" "R2T34"
			(at 0 0 0)
			(layer "B.SilkS")
			(hide yes)
			(effects
				(font
					(size 1.27 1.27)
				)
				(justify mirror)
			)
		)
		(property "Value" ""
			(at 0 0 0)
			(layer "B.Fab")
			(effects
				(font
					(size 1.27 1.27)
				)
				(justify mirror)
			)
		)
		(duplicate_pad_numbers_are_jumpers no)
		(fp_poly
			(pts
				(xy 0.2794 -0.1016) (xy -0.2794 -0.1016) (xy -0.2794 0.9906) (xy 0.2794 0.9906)
			)
			(stroke
				(width 0)
				(type default)
			)
			(fill no)
			(layer "B.CrtYd")
		)
		(fp_line
			(start 0.2794 0.9906)
			(end -0.2794 0.9906)
			(stroke
				(width 0.1)
				(type default)
			)
			(layer "B.Fab")
		)
		(fp_line
			(start 0.2794 -0.1016)
			(end 0.2794 0.9906)
			(stroke
				(width 0.1)
				(type default)
			)
			(layer "B.Fab")
		)
		(fp_line
			(start -0.2794 0.9906)
			(end -0.2794 -0.1016)
			(stroke
				(width 0.1)
				(type default)
			)
			(layer "B.Fab")
		)
		(fp_line
			(start -0.2794 -0.1016)
			(end 0.2794 -0.1016)
			(stroke
				(width 0.1)
				(type default)
			)
			(layer "B.Fab")
		)
		(pad "1" smd rect
			(at 0 0)
			(size 0.508 0.508)
			(layers "B.Cu" "B.Mask" "B.Paste")
			(net "P3V3_STBY")
		)
		(pad "2" smd rect
			(at 0 0.889)
			(size 0.508 0.508)
			(layers "B.Cu" "B.Mask" "B.Paste")
			(net "FM_BMC_PWRBTN_OUT_N")
		)
		(zone
			(layer "B.Cu")
			(hatch none 0.5)
			(connect_pads
				(clearance 0)
			)
			(min_thickness 0.25)
			(keepout
				(tracks not_allowed)
				(vias allowed)
				(pads allowed)
				(copperpour not_allowed)
				(footprints allowed)
			)
			(placement
				(enabled no)
				(sheetname "")
			)
			(fill
				(thermal_gap 0.5)
				(thermal_bridge_width 0.5)
				(island_removal_mode 0)
			)
			(polygon
				(pts
					(xy 398.018 -28.067) (xy 398.526 -28.067) (xy 398.526 -27.686) (xy 398.018 -27.686)
				)
			)
		)
		(zone
			(layer "B.Cu")
			(hatch none 0.5)
			(connect_pads
				(clearance 0)
			)
			(min_thickness 0.25)
			(keepout
				(tracks allowed)
				(vias not_allowed)
				(pads allowed)
				(copperpour not_allowed)
				(footprints allowed)
			)
			(placement
				(enabled no)
				(sheetname "")
			)
			(fill
				(thermal_gap 0.5)
				(thermal_bridge_width 0.5)
				(island_removal_mode 0)
			)
			(polygon
				(pts
					(xy 398.018 -27.686) (xy 398.526 -27.686) (xy 398.526 -28.067) (xy 398.018 -28.067)
				)
			)
		)
	)
	(footprint ""
		(layer "B.Cu")
		(at 370.745258 -75.494642 180)
		(property "Reference" "C3P43"
			(at 0 0 0)
			(layer "B.SilkS")
			(hide yes)
			(effects
				(font
					(size 1.27 1.27)
				)
				(justify mirror)
			)
		)
		(property "Value" ""
			(at 0 0 0)
			(layer "B.Fab")
			(effects
				(font
					(size 1.27 1.27)
				)
				(justify mirror)
			)
		)
		(duplicate_pad_numbers_are_jumpers no)
		(fp_rect
			(start 0.2794 0.9144)
			(end -0.2794 -0.1143)
			(stroke
				(width 0)
				(type default)
			)
			(fill no)
			(layer "B.CrtYd")
		)
		(fp_line
			(start 0.2794 0.9144)
			(end 0.2794 -0.1143)
			(stroke
				(width 0.1)
				(type default)
			)
			(layer "B.Fab")
		)
		(fp_line
			(start 0.2794 -0.1143)
			(end -0.2794 -0.1143)
			(stroke
				(width 0.1)
				(type default)
			)
			(layer "B.Fab")
		)
		(fp_line
			(start -0.2794 0.9144)
			(end 0.2794 0.9144)
			(stroke
				(width 0.1)
				(type default)
			)
			(layer "B.Fab")
		)
		(fp_line
			(start -0.2794 -0.1143)
			(end -0.2794 0.9144)
			(stroke
				(width 0.1)
				(type default)
			)
			(layer "B.Fab")
		)
		(pad "1" smd custom
			(at 0 0 90)
			(size 0.10414 0.10414)
			(layers "B.Cu" "B.Mask" "B.Paste")
			(net "P3V3_STBY")
			(options
				(clearance outline)
				(anchor circle)
			)
			(primitives
				(gr_poly
					(pts
						(xy -0.20828 -0.08636) (xy -0.20828 0.08636) (xy -0.08636 0.20828) (xy 0.086614 0.20828) (xy 0.20828 0.086614)
						(xy 0.20828 -0.08636) (xy 0.08636 -0.20828) (xy -0.08636 -0.20828)
					)
					(width 0)
					(fill yes)
				)
			)
		)
		(pad "2" smd custom
			(at 0 0.8001 90)
			(size 0.10414 0.10414)
			(layers "B.Cu" "B.Mask" "B.Paste")
			(net "GND")
			(options
				(clearance outline)
				(anchor circle)
			)
			(primitives
				(gr_poly
					(pts
						(xy -0.20828 -0.08636) (xy -0.20828 0.08636) (xy -0.08636 0.20828) (xy 0.086614 0.20828) (xy 0.20828 0.086614)
						(xy 0.20828 -0.08636) (xy 0.08636 -0.20828) (xy -0.08636 -0.20828)
					)
					(width 0)
					(fill yes)
				)
			)
		)
		(zone
			(layer "B.Cu")
			(hatch none 0.5)
			(connect_pads
				(clearance 0)
			)
			(min_thickness 0.25)
			(keepout
				(tracks not_allowed)
				(vias allowed)
				(pads allowed)
				(copperpour not_allowed)
				(footprints allowed)
			)
			(placement
				(enabled no)
				(sheetname "")
			)
			(fill
				(thermal_gap 0.5)
				(thermal_bridge_width 0.5)
				(island_removal_mode 0)
			)
			(polygon
				(pts
					(xy 370.657628 -75.704192) (xy 370.657628 -76.085192) (xy 370.832888 -76.085192) (xy 370.833142 -75.704192)
				)
			)
		)
		(zone
			(layer "B.Cu")
			(hatch none 0.5)
			(connect_pads
				(clearance 0)
			)
			(min_thickness 0.25)
			(keepout
				(tracks allowed)
				(vias not_allowed)
				(pads allowed)
				(copperpour not_allowed)
				(footprints allowed)
			)
			(placement
				(enabled no)
				(sheetname "")
			)
			(fill
				(thermal_gap 0.5)
				(thermal_bridge_width 0.5)
				(island_removal_mode 0)
			)
			(polygon
				(pts
					(xy 370.657628 -75.704192) (xy 370.657628 -76.085192) (xy 370.832888 -76.085192) (xy 370.833142 -75.704192)
				)
			)
		)
	)
	(footprint ""
		(layer "B.Cu")
		(at 350.110806 -60.368434)
		(property "Reference" "R2U26"
			(at 0 0 0)
			(layer "B.SilkS")
			(hide yes)
			(effects
				(font
					(size 1.27 1.27)
				)
				(justify mirror)
			)
		)
		(property "Value" ""
			(at 0 0 0)
			(layer "B.Fab")
			(effects
				(font
					(size 1.27 1.27)
				)
				(justify mirror)
			)
		)
		(duplicate_pad_numbers_are_jumpers no)
		(fp_poly
			(pts
				(xy 0.2794 -0.1016) (xy -0.2794 -0.1016) (xy -0.2794 0.9906) (xy 0.2794 0.9906)
			)
			(stroke
				(width 0)
				(type default)
			)
			(fill no)
			(layer "B.CrtYd")
		)
		(fp_line
			(start -0.2794 -0.1016)
			(end 0.2794 -0.1016)
			(stroke
				(width 0.1)
				(type default)
			)
			(layer "B.Fab")
		)
		(fp_line
			(start -0.2794 0.9906)
			(end -0.2794 -0.1016)
			(stroke
				(width 0.1)
				(type default)
			)
			(layer "B.Fab")
		)
		(fp_line
			(start 0.2794 -0.1016)
			(end 0.2794 0.9906)
			(stroke
				(width 0.1)
				(type default)
			)
			(layer "B.Fab")
		)
		(fp_line
			(start 0.2794 0.9906)
			(end -0.2794 0.9906)
			(stroke
				(width 0.1)
				(type default)
			)
			(layer "B.Fab")
		)
		(pad "1" smd rect
			(at 0 0 180)
			(size 0.508 0.508)
			(layers "B.Cu" "B.Mask" "B.Paste")
			(net "P3E_CPU0_PE1_SS_RXP<6>")
		)
		(pad "2" smd rect
			(at 0 0.889 180)
			(size 0.508 0.508)
			(layers "B.Cu" "B.Mask" "B.Paste")
			(net "P3E_CPU0_PE1_SS_R_RXP<6>")
		)
		(zone
			(layer "B.Cu")
			(hatch none 0.5)
			(connect_pads
				(clearance 0)
			)
			(min_thickness 0.25)
			(keepout
				(tracks allowed)
				(vias not_allowed)
				(pads allowed)
				(copperpour not_allowed)
				(footprints allowed)
			)
			(placement
				(enabled no)
				(sheetname "")
			)
			(fill
				(thermal_gap 0.5)
				(thermal_bridge_width 0.5)
				(island_removal_mode 0)
			)
			(polygon
				(pts
					(xy 350.364806 -60.114434) (xy 349.856806 -60.114434) (xy 349.856806 -59.733434) (xy 350.364806 -59.733434)
				)
			)
		)
		(zone
			(layer "B.Cu")
			(hatch none 0.5)
			(connect_pads
				(clearance 0)
			)
			(min_thickness 0.25)
			(keepout
				(tracks not_allowed)
				(vias allowed)
				(pads allowed)
				(copperpour not_allowed)
				(footprints allowed)
			)
			(placement
				(enabled no)
				(sheetname "")
			)
			(fill
				(thermal_gap 0.5)
				(thermal_bridge_width 0.5)
				(island_removal_mode 0)
			)
			(polygon
				(pts
					(xy 350.364806 -59.733434) (xy 349.856806 -59.733434) (xy 349.856806 -60.114434) (xy 350.364806 -60.114434)
				)
			)
		)
	)
)
